(kicad_pcb
	(version 20260206)
	(generator "pcbnew")
	(generator_version "10.0")
	(general
		(thickness 1.6)
		(legacy_teardrops no)
	)
	(paper "A4")
	(title_block
		(title "Bryce Canyon_IOM_IOC_16318-2_OCP.brd")
		(comment 1 "Bryce Canyon / footprint 367 of 1605 (U2), pads 114-227 of 456")
	)
	(layers
		(0 "F.Cu" signal "TOP")
		(4 "In1.Cu" signal "L2GND")
		(6 "In2.Cu" signal "L3")
		(8 "In3.Cu" signal "L4VCC")
		(10 "In4.Cu" signal "L5VCC")
		(12 "In5.Cu" signal "L6")
		(14 "In6.Cu" signal "L7GND")
		(2 "B.Cu" signal "BOTTOM")
		(9 "F.Adhes" user "F.Adhesive")
		(11 "B.Adhes" user "B.Adhesive")
		(13 "F.Paste" user "Package Geometry/Pastemask Top")
		(15 "B.Paste" user "Package Geometry/Pastemask Bottom")
		(5 "F.SilkS" user "Ref Des/Silkscreen Top")
		(7 "B.SilkS" user "Ref Des/Silkscreen Bottom")
		(1 "F.Mask" user "Board Geometry/Soldermask Top")
		(3 "B.Mask" user "Board Geometry/Soldermask Bottom")
		(17 "Dwgs.User" user "User.Drawings")
		(19 "Cmts.User" user "User.Comments")
		(21 "Eco1.User" user "User.Eco1")
		(23 "Eco2.User" user "User.Eco2")
		(25 "Edge.Cuts" user "Board Geometry/Outline")
		(27 "Margin" user)
		(31 "F.CrtYd" user "Package Geometry/Place Bound Top")
		(29 "B.CrtYd" user "Package Geometry/Place Bound Bottom")
		(35 "F.Fab" user "Ref Des/Assembly Top")
		(33 "B.Fab" user "Ref Des/Assembly Bottom")
	)
	(footprint ""
		(layer "F.Cu")
		(at 47.69993 -144.999964 -90)
		(property "Reference" "U2"
			(at 0 0 270)
			(layer "F.SilkS")
			(hide yes)
			(effects
				(font
					(size 1.27 1.27)
				)
			)
		)
		(property "Value" "AST2500A2-GP-GP-U"
			(at -17.0307 -8.584692 270)
			(unlocked yes)
			(layer "F.Fab")
			(hide yes)
			(effects
				(font
					(size 1.016 1.016)
					(thickness 0.1524)
				)
			)
		)
		(property "Device Type" "BGA456D19H58"
			(at -17.0307 -10.108692 270)
			(unlocked yes)
			(layer "F.Fab")
			(hide yes)
			(effects
				(font
					(size 1.016 1.016)
					(thickness 0.1524)
				)
			)
		)
		(duplicate_pad_numbers_are_jumpers no)
		(pad "D4" smd circle
			(at -5.999988 -5.999988 270)
			(size 0.3556 0.3556)
			(layers "F.Cu" "F.Mask" "F.Paste")
			(net "MAC2_TXD3")
		)
		(pad "D5" smd circle
			(at -5.199888 -5.999988 270)
			(size 0.3556 0.3556)
			(layers "F.Cu" "F.Mask" "F.Paste")
			(net "MAC2_TXD2")
		)
		(pad "D6" smd circle
			(at -4.400042 -5.999988 270)
			(size 0.3556 0.3556)
			(layers "F.Cu" "F.Mask" "F.Paste")
			(net "NCSI_RXD1")
		)
		(pad "D7" smd circle
			(at -3.599942 -5.999988 270)
			(size 0.3556 0.3556)
			(layers "F.Cu" "F.Mask" "F.Paste")
			(net "MAC1_TXD3")
		)
		(pad "D8" smd circle
			(at -2.800096 -5.999988 270)
			(size 0.3556 0.3556)
			(layers "F.Cu" "F.Mask" "F.Paste")
			(net "RMII_BMC_MDC_R")
		)
		(pad "D9" smd circle
			(at -1.999996 -5.999988 270)
			(size 0.3556 0.3556)
			(layers "F.Cu" "F.Mask" "F.Paste")
			(net "BMC_SMB11_DAT")
		)
		(pad "D10" smd circle
			(at -1.199896 -5.999988 270)
			(size 0.3556 0.3556)
			(layers "F.Cu" "F.Mask" "F.Paste")
			(net "BMC_SMB12_CLK")
		)
		(pad "D11" smd circle
			(at -0.40005 -5.999988 270)
			(size 0.3556 0.3556)
			(layers "F.Cu" "F.Mask" "F.Paste")
			(net "JTAG_BMC_TDO")
		)
		(pad "D12" smd circle
			(at 0.40005 -5.999988 270)
			(size 0.3556 0.3556)
			(layers "F.Cu" "F.Mask" "F.Paste")
			(net "JTAG_BMC_TDI")
		)
		(pad "D13" smd circle
			(at 1.199896 -5.999988 270)
			(size 0.3556 0.3556)
			(layers "F.Cu" "F.Mask" "F.Paste")
			(net "BMC_TO_EXP_RESET_OUT")
		)
		(pad "D14" smd circle
			(at 1.999996 -5.999988 270)
			(size 0.3556 0.3556)
			(layers "F.Cu" "F.Mask" "F.Paste")
			(net "USB_OCS_N1")
		)
		(pad "D15" smd circle
			(at 2.800096 -5.999988 270)
			(size 0.3556 0.3556)
			(layers "F.Cu" "F.Mask" "F.Paste")
			(net "TP_BMC_GPIOG6")
		)
		(pad "D16" smd circle
			(at 3.599942 -5.999988 270)
			(size 0.3556 0.3556)
			(layers "F.Cu" "F.Mask" "F.Paste")
			(net "TP_BMC_GPIOG5")
		)
		(pad "D17" smd circle
			(at 4.400042 -5.999988 270)
			(size 0.3556 0.3556)
			(layers "F.Cu" "F.Mask" "F.Paste")
			(net "LED_POSTCODE_2")
		)
		(pad "D18" smd circle
			(at 5.199888 -5.999988 270)
			(size 0.3556 0.3556)
			(layers "F.Cu" "F.Mask" "F.Paste")
			(net "LED_POSTCODE_7")
		)
		(pad "D19" smd circle
			(at 5.999988 -5.999988 270)
			(size 0.3556 0.3556)
			(layers "F.Cu" "F.Mask" "F.Paste")
			(net "BMC_EXT1_LED_Y")
		)
		(pad "D20" smd circle
			(at 6.800088 -5.999988 270)
			(size 0.3556 0.3556)
			(layers "F.Cu" "F.Mask" "F.Paste")
			(net "COMP_PWR_BTN_R_N")
		)
		(pad "D21" smd circle
			(at 7.599934 -5.999988 270)
			(size 0.3556 0.3556)
			(layers "F.Cu" "F.Mask" "F.Paste")
			(net "RSTBTN_OUT_N_R")
		)
		(pad "D22" smd circle
			(at 8.400034 -5.999988 270)
			(size 0.3556 0.3556)
			(layers "F.Cu" "F.Mask" "F.Paste")
			(net "TP_BMC0_LPC_LAD2")
		)
		(pad "E1" smd circle
			(at -8.400034 -5.199888 270)
			(size 0.3556 0.3556)
			(layers "F.Cu" "F.Mask" "F.Paste")
			(net "ADC_P1V8_STBY")
		)
		(pad "E2" smd circle
			(at -7.599934 -5.199888 270)
			(size 0.3556 0.3556)
			(layers "F.Cu" "F.Mask" "F.Paste")
			(net "ADC_P3V3_STBY")
		)
		(pad "E3" smd circle
			(at -6.800088 -5.199888 270)
			(size 0.3556 0.3556)
			(layers "F.Cu" "F.Mask" "F.Paste")
			(net "ADC_P1V2_STBY")
		)
		(pad "E4" smd circle
			(at -5.999988 -5.199888 270)
			(size 0.3556 0.3556)
			(layers "F.Cu" "F.Mask" "F.Paste")
			(net "P3V3_STBY")
		)
		(pad "E5" smd circle
			(at -5.199888 -5.199888 270)
			(size 0.3556 0.3556)
			(layers "F.Cu" "F.Mask" "F.Paste")
			(net "GND")
		)
		(pad "E6" smd circle
			(at -4.400042 -5.199888 270)
			(size 0.3556 0.3556)
			(layers "F.Cu" "F.Mask" "F.Paste")
			(net "BMC_RGMII_C2_C3_D1_D2_E6")
		)
		(pad "E7" smd circle
			(at -3.599942 -5.199888 270)
			(size 0.3556 0.3556)
			(layers "F.Cu" "F.Mask" "F.Paste")
			(net "MAC1_TXD2")
		)
		(pad "E8" smd circle
			(at -2.800096 -5.199888 270)
			(size 0.3556 0.3556)
			(layers "F.Cu" "F.Mask" "F.Paste")
			(net "GND")
		)
		(pad "E9" smd circle
			(at -1.999996 -5.199888 270)
			(size 0.3556 0.3556)
			(layers "F.Cu" "F.Mask" "F.Paste")
			(net "NCSI_TXEN")
		)
		(pad "E10" smd circle
			(at -1.199896 -5.199888 270)
			(size 0.3556 0.3556)
			(layers "F.Cu" "F.Mask" "F.Paste")
			(net "RMII_BMC_MDIO_R")
		)
		(pad "E11" smd circle
			(at -0.40005 -5.199888 270)
			(size 0.3556 0.3556)
			(layers "F.Cu" "F.Mask" "F.Paste")
			(net "JTAG_BMC_TRST_N")
		)
		(pad "E12" smd circle
			(at 0.40005 -5.199888 270)
			(size 0.3556 0.3556)
			(layers "F.Cu" "F.Mask" "F.Paste")
			(net "BMC_SMB12_DAT")
		)
		(pad "E13" smd circle
			(at 1.199896 -5.199888 270)
			(size 0.3556 0.3556)
			(layers "F.Cu" "F.Mask" "F.Paste")
			(net "SYS_PWR_LED")
		)
		(pad "E14" smd circle
			(at 1.999996 -5.199888 270)
			(size 0.3556 0.3556)
			(layers "F.Cu" "F.Mask" "F.Paste")
			(net "I2C_COMP_ALERT_N")
		)
		(pad "E15" smd circle
			(at 2.800096 -5.199888 270)
			(size 0.3556 0.3556)
			(layers "F.Cu" "F.Mask" "F.Paste")
			(net "TP_BMC_GPIOI1")
		)
		(pad "E16" smd circle
			(at 3.599942 -5.199888 270)
			(size 0.3556 0.3556)
			(layers "F.Cu" "F.Mask" "F.Paste")
			(net "COMP_SPARE_1_R")
		)
		(pad "E17" smd circle
			(at 4.400042 -5.199888 270)
			(size 0.3556 0.3556)
			(layers "F.Cu" "F.Mask" "F.Paste")
			(net "SYS_RST_EN")
		)
		(pad "E18" smd circle
			(at 5.199888 -5.199888 270)
			(size 0.3556 0.3556)
			(layers "F.Cu" "F.Mask" "F.Paste")
			(net "TP_BMC_EXT1_LED_B")
		)
		(pad "E19" smd circle
			(at 5.999988 -5.199888 270)
			(size 0.3556 0.3556)
			(layers "F.Cu" "F.Mask" "F.Paste")
			(net "SLOTID_1")
		)
		(pad "E20" smd circle
			(at 6.800088 -5.199888 270)
			(size 0.3556 0.3556)
			(layers "F.Cu" "F.Mask" "F.Paste")
			(net "SYS_RESET_N_OUT_R")
		)
		(pad "E21" smd circle
			(at 7.599934 -5.199888 270)
			(size 0.3556 0.3556)
			(layers "F.Cu" "F.Mask" "F.Paste")
			(net "Net_645")
		)
		(pad "E22" smd circle
			(at 8.400034 -5.199888 270)
			(size 0.3556 0.3556)
			(layers "F.Cu" "F.Mask" "F.Paste")
			(net "TP_BMC0_LPC_LAD3")
		)
		(pad "F1" smd circle
			(at -8.400034 -4.400042 270)
			(size 0.3556 0.3556)
			(layers "F.Cu" "F.Mask" "F.Paste")
			(net "GND")
		)
		(pad "F2" smd circle
			(at -7.599934 -4.400042 270)
			(size 0.3556 0.3556)
			(layers "F.Cu" "F.Mask" "F.Paste")
			(net "ADC_P1V8")
		)
		(pad "F3" smd circle
			(at -6.800088 -4.400042 270)
			(size 0.3556 0.3556)
			(layers "F.Cu" "F.Mask" "F.Paste")
			(net "ADC_P2V5_STBY")
		)
		(pad "F4" smd circle
			(at -5.999988 -4.400042 270)
			(size 0.3556 0.3556)
			(layers "F.Cu" "F.Mask" "F.Paste")
			(net "ADC_12V")
		)
		(pad "F5" smd circle
			(at -5.199888 -4.400042 270)
			(size 0.3556 0.3556)
			(layers "F.Cu" "F.Mask" "F.Paste")
			(net "ADC_P5V_STBY")
		)
		(pad "F6" smd circle
			(at -4.400042 -4.400042 270)
			(size 0.3556 0.3556)
			(layers "F.Cu" "F.Mask" "F.Paste")
			(net "P1V15_STBY")
		)
		(pad "F7" smd circle
			(at -3.599942 -4.400042 270)
			(size 0.3556 0.3556)
			(layers "F.Cu" "F.Mask" "F.Paste")
			(net "P3V3_STBY")
		)
		(pad "F8" smd circle
			(at -2.800096 -4.400042 270)
			(size 0.3556 0.3556)
			(layers "F.Cu" "F.Mask" "F.Paste")
			(net "P3V3_STBY")
		)
		(pad "F9" smd circle
			(at -1.999996 -4.400042 270)
			(size 0.3556 0.3556)
			(layers "F.Cu" "F.Mask" "F.Paste")
			(net "NCSI_TXD0_R")
		)
		(pad "F10" smd circle
			(at -1.199896 -4.400042 270)
			(size 0.3556 0.3556)
			(layers "F.Cu" "F.Mask" "F.Paste")
			(net "P3V3_STBY")
		)
		(pad "F11" smd circle
			(at -0.40005 -4.400042 270)
			(size 0.3556 0.3556)
			(layers "F.Cu" "F.Mask" "F.Paste")
			(net "P3V3_STBY")
		)
		(pad "F12" smd circle
			(at 0.40005 -4.400042 270)
			(size 0.3556 0.3556)
			(layers "F.Cu" "F.Mask" "F.Paste")
			(net "P3V3_STBY")
		)
		(pad "F13" smd circle
			(at 1.199896 -4.400042 270)
			(size 0.3556 0.3556)
			(layers "F.Cu" "F.Mask" "F.Paste")
			(net "P3V3_STBY")
		)
		(pad "F14" smd circle
			(at 1.999996 -4.400042 270)
			(size 0.3556 0.3556)
			(layers "F.Cu" "F.Mask" "F.Paste")
			(net "P3V3_STBY")
		)
		(pad "F15" smd circle
			(at 2.800096 -4.400042 270)
			(size 0.3556 0.3556)
			(layers "F.Cu" "F.Mask" "F.Paste")
			(net "P3V3_STBY")
		)
		(pad "F16" smd circle
			(at 3.599942 -4.400042 270)
			(size 0.3556 0.3556)
			(layers "F.Cu" "F.Mask" "F.Paste")
			(net "GND")
		)
		(pad "F17" smd circle
			(at 4.400042 -4.400042 270)
			(size 0.3556 0.3556)
			(layers "F.Cu" "F.Mask" "F.Paste")
			(net "Net_153")
		)
		(pad "F18" smd circle
			(at 5.199888 -4.400042 270)
			(size 0.3556 0.3556)
			(layers "F.Cu" "F.Mask" "F.Paste")
			(net "Net_281")
		)
		(pad "F19" smd circle
			(at 5.999988 -4.400042 270)
			(size 0.3556 0.3556)
			(layers "F.Cu" "F.Mask" "F.Paste")
			(net "Net_644")
		)
		(pad "F20" smd circle
			(at 6.800088 -4.400042 270)
			(size 0.3556 0.3556)
			(layers "F.Cu" "F.Mask" "F.Paste")
			(net "PWRBTN_OUT_N_R")
		)
		(pad "F21" smd circle
			(at 7.599934 -4.400042 270)
			(size 0.3556 0.3556)
			(layers "F.Cu" "F.Mask" "F.Paste")
			(net "LPC_CPU_FRAME_N")
		)
		(pad "F22" smd circle
			(at 8.400034 -4.400042 270)
			(size 0.3556 0.3556)
			(layers "F.Cu" "F.Mask" "F.Paste")
			(net "IRQ_CPU_SERIAL")
		)
		(pad "G1" smd circle
			(at -8.400034 -3.599942 270)
			(size 0.3556 0.3556)
			(layers "F.Cu" "F.Mask" "F.Paste")
			(net "GND")
		)
		(pad "G2" smd circle
			(at -7.599934 -3.599942 270)
			(size 0.3556 0.3556)
			(layers "F.Cu" "F.Mask" "F.Paste")
			(net "ADC_P0V975")
		)
		(pad "G3" smd circle
			(at -6.800088 -3.599942 270)
			(size 0.3556 0.3556)
			(layers "F.Cu" "F.Mask" "F.Paste")
			(net "ADC_P1V5")
		)
		(pad "G4" smd circle
			(at -5.999988 -3.599942 270)
			(size 0.3556 0.3556)
			(layers "F.Cu" "F.Mask" "F.Paste")
			(net "ADC_P3V3")
		)
		(pad "G5" smd circle
			(at -5.199888 -3.599942 270)
			(size 0.3556 0.3556)
			(layers "F.Cu" "F.Mask" "F.Paste")
			(net "ADC_P1V15_STBY")
		)
		(pad "G6" smd circle
			(at -4.400042 -3.599942 270)
			(size 0.3556 0.3556)
			(layers "F.Cu" "F.Mask" "F.Paste")
			(net "GND")
		)
		(pad "G7" smd circle
			(at -3.599942 -3.599942 270)
			(size 0.3556 0.3556)
			(layers "F.Cu" "F.Mask" "F.Paste")
			(net "P1V15_STBY")
		)
		(pad "G8" smd circle
			(at -2.800096 -3.599942 270)
			(size 0.3556 0.3556)
			(layers "F.Cu" "F.Mask" "F.Paste")
			(net "P1V15_STBY")
		)
		(pad "G9" smd circle
			(at -1.999996 -3.599942 270)
			(size 0.3556 0.3556)
			(layers "F.Cu" "F.Mask" "F.Paste")
			(net "P1V15_STBY")
		)
		(pad "G10" smd circle
			(at -1.199896 -3.599942 270)
			(size 0.3556 0.3556)
			(layers "F.Cu" "F.Mask" "F.Paste")
			(net "P1V15_STBY")
		)
		(pad "G11" smd circle
			(at -0.40005 -3.599942 270)
			(size 0.3556 0.3556)
			(layers "F.Cu" "F.Mask" "F.Paste")
			(net "P1V15_STBY")
		)
		(pad "G12" smd circle
			(at 0.40005 -3.599942 270)
			(size 0.3556 0.3556)
			(layers "F.Cu" "F.Mask" "F.Paste")
			(net "P1V15_STBY")
		)
		(pad "G13" smd circle
			(at 1.199896 -3.599942 270)
			(size 0.3556 0.3556)
			(layers "F.Cu" "F.Mask" "F.Paste")
			(net "P1V15_STBY")
		)
		(pad "G14" smd circle
			(at 1.999996 -3.599942 270)
			(size 0.3556 0.3556)
			(layers "F.Cu" "F.Mask" "F.Paste")
			(net "P1V15_STBY")
		)
		(pad "G15" smd circle
			(at 2.800096 -3.599942 270)
			(size 0.3556 0.3556)
			(layers "F.Cu" "F.Mask" "F.Paste")
			(net "P1V15_STBY")
		)
		(pad "G16" smd circle
			(at 3.599942 -3.599942 270)
			(size 0.3556 0.3556)
			(layers "F.Cu" "F.Mask" "F.Paste")
			(net "P3V3_STBY")
		)
		(pad "G17" smd circle
			(at 4.400042 -3.599942 270)
			(size 0.3556 0.3556)
			(layers "F.Cu" "F.Mask" "F.Paste")
			(net "P12V_A_PGOOD_R")
		)
		(pad "G18" smd circle
			(at 5.199888 -3.599942 270)
			(size 0.3556 0.3556)
			(layers "F.Cu" "F.Mask" "F.Paste")
			(net "Net_643")
		)
		(pad "G19" smd circle
			(at 5.999988 -3.599942 270)
			(size 0.3556 0.3556)
			(layers "F.Cu" "F.Mask" "F.Paste")
			(net "GND")
		)
		(pad "G20" smd circle
			(at 6.800088 -3.599942 270)
			(size 0.3556 0.3556)
			(layers "F.Cu" "F.Mask" "F.Paste")
			(net "TP_BMC0_LPC_LAD1")
		)
		(pad "G21" smd circle
			(at 7.599934 -3.599942 270)
			(size 0.3556 0.3556)
			(layers "F.Cu" "F.Mask" "F.Paste")
			(net "TP_BMC0_LPC_LAD0")
		)
		(pad "G22" smd circle
			(at 8.400034 -3.599942 270)
			(size 0.3556 0.3556)
			(layers "F.Cu" "F.Mask" "F.Paste")
			(net "LPCRST0_N")
		)
		(pad "H1" smd circle
			(at -8.400034 -2.800096 270)
			(size 0.3556 0.3556)
			(layers "F.Cu" "F.Mask" "F.Paste")
			(net "ADCVREFFN")
		)
		(pad "H2" smd circle
			(at -7.599934 -2.800096 270)
			(size 0.3556 0.3556)
			(layers "F.Cu" "F.Mask" "F.Paste")
			(net "ADCVREFFP")
		)
		(pad "H3" smd circle
			(at -6.800088 -2.800096 270)
			(size 0.3556 0.3556)
			(layers "F.Cu" "F.Mask" "F.Paste")
			(net "GND")
		)
		(pad "H4" smd circle
			(at -5.999988 -2.800096 270)
			(size 0.3556 0.3556)
			(layers "F.Cu" "F.Mask" "F.Paste")
			(net "GND")
		)
		(pad "H5" smd circle
			(at -5.199888 -2.800096 270)
			(size 0.3556 0.3556)
			(layers "F.Cu" "F.Mask" "F.Paste")
			(net "GND")
		)
		(pad "H6" smd circle
			(at -4.400042 -2.800096 270)
			(size 0.3556 0.3556)
			(layers "F.Cu" "F.Mask" "F.Paste")
			(net "GND")
		)
		(pad "H7" smd circle
			(at -3.599942 -2.800096 270)
			(size 0.3556 0.3556)
			(layers "F.Cu" "F.Mask" "F.Paste")
			(net "VPLLAV33")
		)
		(pad "H16" smd circle
			(at 3.599942 -2.800096 270)
			(size 0.3556 0.3556)
			(layers "F.Cu" "F.Mask" "F.Paste")
			(net "P1V15_STBY")
		)
		(pad "H17" smd circle
			(at 4.400042 -2.800096 270)
			(size 0.3556 0.3556)
			(layers "F.Cu" "F.Mask" "F.Paste")
			(net "P3V3_STBY")
		)
		(pad "H18" smd circle
			(at 5.199888 -2.800096 270)
			(size 0.3556 0.3556)
			(layers "F.Cu" "F.Mask" "F.Paste")
			(net "SCC_RMT_TYPE_0_R")
		)
		(pad "H19" smd circle
			(at 5.999988 -2.800096 270)
			(size 0.3556 0.3556)
			(layers "F.Cu" "F.Mask" "F.Paste")
			(net "DPB_MISC_ALERT_O_R")
		)
		(pad "H20" smd circle
			(at 6.800088 -2.800096 270)
			(size 0.3556 0.3556)
			(layers "F.Cu" "F.Mask" "F.Paste")
			(net "Net_642")
		)
		(pad "H21" smd circle
			(at 7.599934 -2.800096 270)
			(size 0.3556 0.3556)
			(layers "F.Cu" "F.Mask" "F.Paste")
			(net "TP_M2_2_ALERT#")
		)
		(pad "H22" smd circle
			(at 8.400034 -2.800096 270)
			(size 0.3556 0.3556)
			(layers "F.Cu" "F.Mask" "F.Paste")
			(net "Net_641")
		)
		(pad "J1" smd circle
			(at -8.400034 -1.999996 270)
			(size 0.3556 0.3556)
			(layers "F.Cu" "F.Mask" "F.Paste")
			(net "ADCVREXT")
		)
		(pad "J2" smd circle
			(at -7.599934 -1.999996 270)
			(size 0.3556 0.3556)
			(layers "F.Cu" "F.Mask" "F.Paste")
			(net "Net_657")
		)
		(pad "J3" smd circle
			(at -6.800088 -1.999996 270)
			(size 0.3556 0.3556)
			(layers "F.Cu" "F.Mask" "F.Paste")
			(net "Net_656")
		)
		(pad "J4" smd circle
			(at -5.999988 -1.999996 270)
			(size 0.3556 0.3556)
			(layers "F.Cu" "F.Mask" "F.Paste")
			(net "Net_655")
		)
		(pad "J5" smd circle
			(at -5.199888 -1.999996 270)
			(size 0.3556 0.3556)
			(layers "F.Cu" "F.Mask" "F.Paste")
			(net "GND")
		)
		(pad "J6" smd circle
			(at -4.400042 -1.999996 270)
			(size 0.3556 0.3556)
			(layers "F.Cu" "F.Mask" "F.Paste")
			(net "ADCAV33")
		)
		(pad "J7" smd circle
			(at -3.599942 -1.999996 270)
			(size 0.3556 0.3556)
			(layers "F.Cu" "F.Mask" "F.Paste")
			(net "VPLLAV33")
		)
		(pad "J9" smd circle
			(at -1.999996 -1.999996 270)
			(size 0.3556 0.3556)
			(layers "F.Cu" "F.Mask" "F.Paste")
			(net "GND")
		)
		(pad "J10" smd circle
			(at -1.199896 -1.999996 270)
			(size 0.3556 0.3556)
			(layers "F.Cu" "F.Mask" "F.Paste")
			(net "GND")
		)
		(pad "J11" smd circle
			(at -0.40005 -1.999996 270)
			(size 0.3556 0.3556)
			(layers "F.Cu" "F.Mask" "F.Paste")
			(net "GND")
		)
		(pad "J12" smd circle
			(at 0.40005 -1.999996 270)
			(size 0.3556 0.3556)
			(layers "F.Cu" "F.Mask" "F.Paste")
			(net "GND")
		)
		(pad "J13" smd circle
			(at 1.199896 -1.999996 270)
			(size 0.3556 0.3556)
			(layers "F.Cu" "F.Mask" "F.Paste")
			(net "GND")
		)
		(pad "J14" smd circle
			(at 1.999996 -1.999996 270)
			(size 0.3556 0.3556)
			(layers "F.Cu" "F.Mask" "F.Paste")
			(net "GND")
		)
		(pad "J16" smd circle
			(at 3.599942 -1.999996 270)
			(size 0.3556 0.3556)
			(layers "F.Cu" "F.Mask" "F.Paste")
			(net "P1V15_STBY")
		)
		(pad "J17" smd circle
			(at 4.400042 -1.999996 270)
			(size 0.3556 0.3556)
			(layers "F.Cu" "F.Mask" "F.Paste")
			(net "P1V8_STBY")
		)
	)
)
